(kicad_pcb
	(version 20241229)
	(generator "pcbnew")
	(generator_version "9.0")
	(general
		(thickness 1.62)
		(legacy_teardrops no)
	)
	(paper "A3")
	(title_block
		(title "COM Express 7 Baseboard")
		(date "2025-02-04")
		(rev "1.1.2")
		(company "Antmicro Ltd")
		(comment 1 "www.antmicro.com")
		(comment 9 "footprints 335-339 of 802")
	)
	(layers
		(0 "F.Cu" signal)
		(4 "In1.Cu" signal)
		(6 "In2.Cu" signal)
		(8 "In3.Cu" signal)
		(10 "In4.Cu" signal)
		(12 "In5.Cu" signal)
		(14 "In6.Cu" signal)
		(2 "B.Cu" signal)
		(9 "F.Adhes" user "F.Adhesive")
		(11 "B.Adhes" user "B.Adhesive")
		(13 "F.Paste" user)
		(15 "B.Paste" user)
		(5 "F.SilkS" user "F.Silkscreen")
		(7 "B.SilkS" user "B.Silkscreen")
		(1 "F.Mask" user)
		(3 "B.Mask" user)
		(17 "Dwgs.User" user "User.Drawings")
		(19 "Cmts.User" user "User.Comments")
		(21 "Eco1.User" user "User.Eco1")
		(23 "Eco2.User" user "User.Eco2")
		(25 "Edge.Cuts" user)
		(27 "Margin" user)
		(31 "F.CrtYd" user "F.Courtyard")
		(29 "B.CrtYd" user "B.Courtyard")
		(35 "F.Fab" user)
		(33 "B.Fab" user)
	)
	(footprint "antmicro-footprints:R_0402_1005Metric"
		(layer "F.Cu")
		(at 261.54 83.349999 90)
		(descr "Resistor SMD 0402")
		(tags "resistor SMD 0402")
		(property "Reference" "R155"
			(at -1.460001 1.36 90)
			(layer "F.SilkS")
			(effects
				(font
					(size 0.7 0.7)
					(thickness 0.15)
				)
				(justify left bottom)
			)
		)
		(property "Value" "R_10k_0402"
			(at -1.011843 1.772047 90)
			(layer "F.Fab")
			(effects
				(font
					(size 0.7 0.7)
					(thickness 0.15)
				)
				(justify left bottom)
			)
		)
		(property "Datasheet" "https://www.bourns.com/docs/product-datasheets/cr.pdf"
			(at 0 0 90)
			(layer "F.Fab")
			(hide yes)
			(effects
				(font
					(size 1.27 1.27)
					(thickness 0.15)
				)
			)
		)
		(property "Author" "Antmicro"
			(at 344.889999 -178.190001 0)
			(layer "F.Fab")
			(hide yes)
			(effects
				(font
					(size 1 1)
					(thickness 0.15)
				)
			)
		)
		(property "License" "Apache-2.0"
			(at 344.889999 -178.190001 0)
			(layer "F.Fab")
			(hide yes)
			(effects
				(font
					(size 1 1)
					(thickness 0.15)
				)
			)
		)
		(property "MPN" "CR0402-FX-1002GLF"
			(at 344.889999 -178.190001 0)
			(layer "F.Fab")
			(hide yes)
			(effects
				(font
					(size 1 1)
					(thickness 0.15)
				)
			)
		)
		(property "Manufacturer" "Bourns"
			(at 344.889999 -178.190001 0)
			(layer "F.Fab")
			(hide yes)
			(effects
				(font
					(size 1 1)
					(thickness 0.15)
				)
			)
		)
		(property "Public" "False"
			(at 344.889999 -178.190001 0)
			(layer "F.Fab")
			(hide yes)
			(effects
				(font
					(size 1 1)
					(thickness 0.15)
				)
			)
		)
		(property "Tolerance" "1%"
			(at 344.889999 -178.190001 0)
			(layer "F.Fab")
			(hide yes)
			(effects
				(font
					(size 1 1)
					(thickness 0.15)
				)
			)
		)
		(property "Val" "10k"
			(at 344.889999 -178.190001 0)
			(layer "F.Fab")
			(hide yes)
			(effects
				(font
					(size 1 1)
					(thickness 0.15)
				)
			)
		)
		(sheetname "Misc")
		(sheetfile "misc.kicad_sch")
		(attr smd)
		(fp_rect
			(start -0.925 -0.47)
			(end 0.925 0.47)
			(stroke
				(width 0.05)
				(type default)
			)
			(fill no)
			(layer "F.CrtYd")
		)
		(fp_rect
			(start -0.5 -0.25)
			(end 0.5 0.25)
			(stroke
				(width 0.15)
				(type solid)
			)
			(fill no)
			(layer "F.Fab")
		)
		(pad "1" smd roundrect
			(at -0.48 0 90)
			(size 0.59 0.64)
			(layers "F.Cu" "F.Mask" "F.Paste")
			(roundrect_rratio 0.25)
			(net 596 "/Misc/PWM2")
			(pintype "passive")
			(teardrops
				(best_length_ratio 0.2)
				(max_length 1)
				(best_width_ratio 0.9)
				(max_width 2)
				(curved_edges yes)
				(filter_ratio 0.9)
				(enabled yes)
				(allow_two_segments yes)
				(prefer_zone_connections yes)
			)
		)
		(pad "2" smd roundrect
			(at 0.48 0 90)
			(size 0.59 0.64)
			(layers "F.Cu" "F.Mask" "F.Paste")
			(roundrect_rratio 0.25)
			(net 2 "+3V3")
			(pintype "passive")
			(teardrops
				(best_length_ratio 0.2)
				(max_length 1)
				(best_width_ratio 0.9)
				(max_width 2)
				(curved_edges yes)
				(filter_ratio 0.9)
				(enabled yes)
				(allow_two_segments yes)
				(prefer_zone_connections yes)
			)
		)
	)
	(footprint "antmicro-footprints:C_0402_1005Metric"
		(layer "F.Cu")
		(at 120.4 148.421 -90)
		(descr "Capacitor SMD 0402")
		(tags "capacitor SMD 0402")
		(property "Reference" "C127"
			(at -12.611 -0.6 90)
			(layer "F.SilkS")
			(effects
				(font
					(size 0.7 0.7)
					(thickness 0.15)
				)
				(justify right bottom)
			)
		)
		(property "Value" "C_100n_0402"
			(at -1.022927 2.155213 90)
			(layer "F.Fab")
			(effects
				(font
					(size 0.7 0.7)
					(thickness 0.15)
				)
				(justify right bottom)
			)
		)
		(property "Datasheet" "https://www.murata.com/products/productdetail?partno=GRM155R61H104KE14%23"
			(at 0 0 270)
			(layer "F.Fab")
			(hide yes)
			(effects
				(font
					(size 1.27 1.27)
					(thickness 0.15)
				)
			)
		)
		(property "Author" "Antmicro"
			(at -28.021 268.821 0)
			(layer "F.Fab")
			(hide yes)
			(effects
				(font
					(size 1 1)
					(thickness 0.15)
				)
			)
		)
		(property "Dielectric" "X5R"
			(at -28.021 268.821 0)
			(layer "F.Fab")
			(hide yes)
			(effects
				(font
					(size 1 1)
					(thickness 0.15)
				)
			)
		)
		(property "License" "Apache-2.0"
			(at -28.021 268.821 0)
			(layer "F.Fab")
			(hide yes)
			(effects
				(font
					(size 1 1)
					(thickness 0.15)
				)
			)
		)
		(property "MPN" "GRM155R61H104KE14D"
			(at -28.021 268.821 0)
			(layer "F.Fab")
			(hide yes)
			(effects
				(font
					(size 1 1)
					(thickness 0.15)
				)
			)
		)
		(property "Manufacturer" "Murata"
			(at -28.021 268.821 0)
			(layer "F.Fab")
			(hide yes)
			(effects
				(font
					(size 1 1)
					(thickness 0.15)
				)
			)
		)
		(property "Public" "False"
			(at -28.021 268.821 0)
			(layer "F.Fab")
			(hide yes)
			(effects
				(font
					(size 1 1)
					(thickness 0.15)
				)
			)
		)
		(property "Val" "100n"
			(at -28.021 268.821 0)
			(layer "F.Fab")
			(hide yes)
			(effects
				(font
					(size 1 1)
					(thickness 0.15)
				)
			)
		)
		(property "Voltage" "50V"
			(at -28.021 268.821 0)
			(layer "F.Fab")
			(hide yes)
			(effects
				(font
					(size 1 1)
					(thickness 0.15)
				)
			)
		)
		(sheetname "PCIe redriver")
		(sheetfile "pcie_redriver.kicad_sch")
		(attr smd)
		(fp_rect
			(start -0.925 -0.47)
			(end 0.925 0.47)
			(stroke
				(width 0.05)
				(type default)
			)
			(fill no)
			(layer "F.CrtYd")
		)
		(fp_line
			(start -0.494 0.248)
			(end -0.494 -0.25)
			(stroke
				(width 0.15)
				(type solid)
			)
			(layer "F.Fab")
		)
		(fp_line
			(start 0.504 0.248)
			(end -0.494 0.248)
			(stroke
				(width 0.15)
				(type solid)
			)
			(layer "F.Fab")
		)
		(fp_line
			(start -0.494 -0.25)
			(end 0.504 -0.25)
			(stroke
				(width 0.15)
				(type solid)
			)
			(layer "F.Fab")
		)
		(fp_line
			(start 0.504 -0.25)
			(end 0.504 0.248)
			(stroke
				(width 0.15)
				(type solid)
			)
			(layer "F.Fab")
		)
		(pad "1" smd roundrect
			(at -0.48 0 270)
			(size 0.59 0.64)
			(layers "F.Cu" "F.Mask" "F.Paste")
			(roundrect_rratio 0.25)
			(net 1 "GND")
			(pintype "passive")
			(teardrops
				(best_length_ratio 0.2)
				(max_length 1)
				(best_width_ratio 0.9)
				(max_width 2)
				(curved_edges yes)
				(filter_ratio 0.9)
				(enabled yes)
				(allow_two_segments yes)
				(prefer_zone_connections yes)
			)
		)
		(pad "2" smd roundrect
			(at 0.48 0 270)
			(size 0.59 0.64)
			(layers "F.Cu" "F.Mask" "F.Paste")
			(roundrect_rratio 0.25)
			(net 2 "+3V3")
			(pintype "passive")
			(teardrops
				(best_length_ratio 0.2)
				(max_length 1)
				(best_width_ratio 0.9)
				(max_width 2)
				(curved_edges yes)
				(filter_ratio 0.9)
				(enabled yes)
				(allow_two_segments yes)
				(prefer_zone_connections yes)
			)
		)
	)
	(footprint "antmicro-footprints:Mech_Lightpipe_Bivar_SLP3-300-250-F"
		(layer "F.Cu")
		(at 105.1505 71.051 -90)
		(property "Reference" "H4"
			(at 0.559 -1.5995 270)
			(unlocked yes)
			(layer "F.SilkS")
			(effects
				(font
					(size 0.7 0.7)
					(thickness 0.15)
				)
				(justify left bottom)
			)
		)
		(property "Value" "Lightpipe_Bivar_SLP3-300-250-F"
			(at 0 6.6 270)
			(unlocked yes)
			(layer "F.Fab")
			(effects
				(font
					(size 0.7 0.7)
					(thickness 0.15)
				)
				(justify left bottom)
			)
		)
		(property "Datasheet" "https://www.bivar.com/parts_content/Datasheets/SLP3-XXX-XXX-X.pdf"
			(at 0 0 90)
			(layer "F.Fab")
			(hide yes)
			(effects
				(font
					(size 1.27 1.27)
					(thickness 0.15)
				)
			)
		)
		(property "Manufacturer" "BIVAR"
			(at 0 0 270)
			(unlocked yes)
			(layer "F.Fab")
			(hide yes)
			(effects
				(font
					(size 1 1)
					(thickness 0.15)
				)
			)
		)
		(property "MPN" "SLP3-150-300-F"
			(at 0 0 270)
			(unlocked yes)
			(layer "F.Fab")
			(hide yes)
			(effects
				(font
					(size 1 1)
					(thickness 0.15)
				)
			)
		)
		(property "Author" "Antmicro"
			(at 0 0 270)
			(unlocked yes)
			(layer "F.Fab")
			(hide yes)
			(effects
				(font
					(size 1 1)
					(thickness 0.15)
				)
			)
		)
		(property "License" "Apache-2.0"
			(at 0 0 270)
			(unlocked yes)
			(layer "F.Fab")
			(hide yes)
			(effects
				(font
					(size 1 1)
					(thickness 0.15)
				)
			)
		)
		(sheetname "Misc")
		(sheetfile "misc.kicad_sch")
		(attr through_hole)
		(fp_rect
			(start -1.04 -1.225)
			(end 3.559 5.326)
			(stroke
				(width 0.15)
				(type solid)
			)
			(fill no)
			(layer "F.SilkS")
		)
		(fp_rect
			(start -1.3 4.196)
			(end 3.819 5.596)
			(stroke
				(width 0.05)
				(type solid)
			)
			(fill no)
			(layer "F.CrtYd")
		)
		(fp_rect
			(start -1.301 -1.504)
			(end 3.819 1.196)
			(stroke
				(width 0.05)
				(type solid)
			)
			(fill no)
			(layer "F.CrtYd")
		)
		(fp_line
			(start 0.55 2.5)
			(end 1.25 2.5)
			(stroke
				(width 0.15)
				(type solid)
			)
			(layer "F.Fab")
		)
		(fp_line
			(start 1.25 2.5)
			(end 1.25 3.201)
			(stroke
				(width 0.15)
				(type solid)
			)
			(layer "F.Fab")
		)
		(fp_line
			(start 1.25 2.5)
			(end 1.95 2.5)
			(stroke
				(width 0.15)
				(type solid)
			)
			(layer "F.Fab")
		)
		(fp_line
			(start 1.25 1.8)
			(end 1.25 2.5)
			(stroke
				(width 0.15)
				(type solid)
			)
			(layer "F.Fab")
		)
		(fp_rect
			(start -0.791 1.376)
			(end 3.309 3.625)
			(stroke
				(width 0.15)
				(type solid)
			)
			(fill no)
			(layer "F.Fab")
		)
		(pad "" np_thru_hole circle
			(at 0 0 270)
			(size 1.2 1.2)
			(drill 1.3208)
			(layers "F&B.Cu" "*.Mask")
		)
		(pad "" np_thru_hole circle
			(at 2.5 0 270)
			(size 1.2 1.2)
			(drill 1.3208)
			(layers "F&B.Cu" "*.Mask")
		)
	)
	(footprint "antmicro-footprints:C_0402_1005Metric"
		(layer "F.Cu")
		(at 117.4 148.421 -90)
		(descr "Capacitor SMD 0402")
		(tags "capacitor SMD 0402")
		(property "Reference" "C115"
			(at -12.611 -1.6 90)
			(layer "F.SilkS")
			(effects
				(font
					(size 0.7 0.7)
					(thickness 0.15)
				)
				(justify right bottom)
			)
		)
		(property "Value" "C_100n_0402"
			(at -1.022927 2.155213 90)
			(layer "F.Fab")
			(effects
				(font
					(size 0.7 0.7)
					(thickness 0.15)
				)
				(justify right bottom)
			)
		)
		(property "Datasheet" "https://www.murata.com/products/productdetail?partno=GRM155R61H104KE14%23"
			(at 0 0 270)
			(layer "F.Fab")
			(hide yes)
			(effects
				(font
					(size 1.27 1.27)
					(thickness 0.15)
				)
			)
		)
		(property "Author" "Antmicro"
			(at -31.021 265.821 0)
			(layer "F.Fab")
			(hide yes)
			(effects
				(font
					(size 1 1)
					(thickness 0.15)
				)
			)
		)
		(property "Dielectric" "X5R"
			(at -31.021 265.821 0)
			(layer "F.Fab")
			(hide yes)
			(effects
				(font
					(size 1 1)
					(thickness 0.15)
				)
			)
		)
		(property "License" "Apache-2.0"
			(at -31.021 265.821 0)
			(layer "F.Fab")
			(hide yes)
			(effects
				(font
					(size 1 1)
					(thickness 0.15)
				)
			)
		)
		(property "MPN" "GRM155R61H104KE14D"
			(at -31.021 265.821 0)
			(layer "F.Fab")
			(hide yes)
			(effects
				(font
					(size 1 1)
					(thickness 0.15)
				)
			)
		)
		(property "Manufacturer" "Murata"
			(at -31.021 265.821 0)
			(layer "F.Fab")
			(hide yes)
			(effects
				(font
					(size 1 1)
					(thickness 0.15)
				)
			)
		)
		(property "Public" "False"
			(at -31.021 265.821 0)
			(layer "F.Fab")
			(hide yes)
			(effects
				(font
					(size 1 1)
					(thickness 0.15)
				)
			)
		)
		(property "Val" "100n"
			(at -31.021 265.821 0)
			(layer "F.Fab")
			(hide yes)
			(effects
				(font
					(size 1 1)
					(thickness 0.15)
				)
			)
		)
		(property "Voltage" "50V"
			(at -31.021 265.821 0)
			(layer "F.Fab")
			(hide yes)
			(effects
				(font
					(size 1 1)
					(thickness 0.15)
				)
			)
		)
		(sheetname "PCIe redriver")
		(sheetfile "pcie_redriver.kicad_sch")
		(attr smd)
		(fp_rect
			(start -0.925 -0.47)
			(end 0.925 0.47)
			(stroke
				(width 0.05)
				(type default)
			)
			(fill no)
			(layer "F.CrtYd")
		)
		(fp_line
			(start -0.494 0.248)
			(end -0.494 -0.25)
			(stroke
				(width 0.15)
				(type solid)
			)
			(layer "F.Fab")
		)
		(fp_line
			(start 0.504 0.248)
			(end -0.494 0.248)
			(stroke
				(width 0.15)
				(type solid)
			)
			(layer "F.Fab")
		)
		(fp_line
			(start -0.494 -0.25)
			(end 0.504 -0.25)
			(stroke
				(width 0.15)
				(type solid)
			)
			(layer "F.Fab")
		)
		(fp_line
			(start 0.504 -0.25)
			(end 0.504 0.248)
			(stroke
				(width 0.15)
				(type solid)
			)
			(layer "F.Fab")
		)
		(pad "1" smd roundrect
			(at -0.48 0 270)
			(size 0.59 0.64)
			(layers "F.Cu" "F.Mask" "F.Paste")
			(roundrect_rratio 0.25)
			(net 1 "GND")
			(pintype "passive")
			(teardrops
				(best_length_ratio 0.2)
				(max_length 1)
				(best_width_ratio 0.9)
				(max_width 2)
				(curved_edges yes)
				(filter_ratio 0.9)
				(enabled yes)
				(allow_two_segments yes)
				(prefer_zone_connections yes)
			)
		)
		(pad "2" smd roundrect
			(at 0.48 0 270)
			(size 0.59 0.64)
			(layers "F.Cu" "F.Mask" "F.Paste")
			(roundrect_rratio 0.25)
			(net 2 "+3V3")
			(pintype "passive")
			(teardrops
				(best_length_ratio 0.2)
				(max_length 1)
				(best_width_ratio 0.9)
				(max_width 2)
				(curved_edges yes)
				(filter_ratio 0.9)
				(enabled yes)
				(allow_two_segments yes)
				(prefer_zone_connections yes)
			)
		)
	)
	(footprint "antmicro-footprints:C_0402_1005Metric"
		(layer "F.Cu")
		(at 302.500002 90.06 180)
		(descr "Capacitor SMD 0402")
		(tags "capacitor SMD 0402")
		(property "Reference" "C205"
			(at -1.399998 0.45 0)
			(layer "F.SilkS")
			(effects
				(font
					(size 0.7 0.7)
					(thickness 0.15)
				)
				(justify right bottom)
			)
		)
		(property "Value" "C_100n_0402"
			(at -1.022927 2.155213 0)
			(layer "F.Fab")
			(effects
				(font
					(size 0.7 0.7)
					(thickness 0.15)
				)
				(justify right bottom)
			)
		)
		(property "Datasheet" "https://www.murata.com/products/productdetail?partno=GRM155R61H104KE14%23"
			(at 0 0 180)
			(layer "F.Fab")
			(hide yes)
			(effects
				(font
					(size 1.27 1.27)
					(thickness 0.15)
				)
			)
		)
		(property "Author" "Antmicro"
			(at 605.000004 180.12 0)
			(layer "F.Fab")
			(hide yes)
			(effects
				(font
					(size 1 1)
					(thickness 0.15)
				)
			)
		)
		(property "Dielectric" "X5R"
			(at 605.000004 180.12 0)
			(layer "F.Fab")
			(hide yes)
			(effects
				(font
					(size 1 1)
					(thickness 0.15)
				)
			)
		)
		(property "License" "Apache-2.0"
			(at 605.000004 180.12 0)
			(layer "F.Fab")
			(hide yes)
			(effects
				(font
					(size 1 1)
					(thickness 0.15)
				)
			)
		)
		(property "MPN" "GRM155R61H104KE14D"
			(at 605.000004 180.12 0)
			(layer "F.Fab")
			(hide yes)
			(effects
				(font
					(size 1 1)
					(thickness 0.15)
				)
			)
		)
		(property "Manufacturer" "Murata"
			(at 605.000004 180.12 0)
			(layer "F.Fab")
			(hide yes)
			(effects
				(font
					(size 1 1)
					(thickness 0.15)
				)
			)
		)
		(property "Public" "False"
			(at 605.000004 180.12 0)
			(layer "F.Fab")
			(hide yes)
			(effects
				(font
					(size 1 1)
					(thickness 0.15)
				)
			)
		)
		(property "Val" "100n"
			(at 605.000004 180.12 0)
			(layer "F.Fab")
			(hide yes)
			(effects
				(font
					(size 1 1)
					(thickness 0.15)
				)
			)
		)
		(property "Voltage" "50V"
			(at 605.000004 180.12 0)
			(layer "F.Fab")
			(hide yes)
			(effects
				(font
					(size 1 1)
					(thickness 0.15)
				)
			)
		)
		(sheetname "Power")
		(sheetfile "power.kicad_sch")
		(attr smd)
		(fp_rect
			(start -0.925 -0.47)
			(end 0.925 0.47)
			(stroke
				(width 0.05)
				(type default)
			)
			(fill no)
			(layer "F.CrtYd")
		)
		(fp_line
			(start 0.504 0.248)
			(end -0.494 0.248)
			(stroke
				(width 0.15)
				(type solid)
			)
			(layer "F.Fab")
		)
		(fp_line
			(start 0.504 -0.25)
			(end 0.504 0.248)
			(stroke
				(width 0.15)
				(type solid)
			)
			(layer "F.Fab")
		)
		(fp_line
			(start -0.494 0.248)
			(end -0.494 -0.25)
			(stroke
				(width 0.15)
				(type solid)
			)
			(layer "F.Fab")
		)
		(fp_line
			(start -0.494 -0.25)
			(end 0.504 -0.25)
			(stroke
				(width 0.15)
				(type solid)
			)
			(layer "F.Fab")
		)
		(pad "1" smd roundrect
			(at -0.48 0 180)
			(size 0.59 0.64)
			(layers "F.Cu" "F.Mask" "F.Paste")
			(roundrect_rratio 0.25)
			(net 1 "GND")
			(pintype "passive")
			(teardrops
				(best_length_ratio 0.2)
				(max_length 1)
				(best_width_ratio 0.9)
				(max_width 2)
				(curved_edges yes)
				(filter_ratio 0.9)
				(enabled yes)
				(allow_two_segments yes)
				(prefer_zone_connections yes)
			)
		)
		(pad "2" smd roundrect
			(at 0.48 0 180)
			(size 0.59 0.64)
			(layers "F.Cu" "F.Mask" "F.Paste")
			(roundrect_rratio 0.25)
			(net 73 "+3V3_AON")
			(pintype "passive")
			(teardrops
				(best_length_ratio 0.2)
				(max_length 1)
				(best_width_ratio 0.9)
				(max_width 2)
				(curved_edges yes)
				(filter_ratio 0.9)
				(enabled yes)
				(allow_two_segments yes)
				(prefer_zone_connections yes)
			)
		)
	)
)
